# T6G (Grand Teton) — schematic netlist excerpt (pin names and nets, part order shuffled) for the footprints in the layout excerpt that follows; sources: Cadence DE-HDL packaged netlist, KiCad conversion of 04192023_DAF0TMB3IC0_F0TG_MB_C_brd_V02_OCP.brd

C2557  Q_CAP  22UF 4V 20% X6S  pkg C0402  page 70 : A = PVDDCR_SOC_P0 ; B = GND
PR8009  Q_RES  0 5% CHIP  pkg 0402LF  page 210 : A = SVID_PVDDCR_CPU0_P1_SVC_R ; B = SVID_PVDDCR_CPU0_P1_SVC_R1

(kicad_pcb
	(version 20260206)
	(generator "pcbnew")
	(generator_version "10.0")
	(general
		(thickness 1.6)
		(legacy_teardrops no)
	)
	(paper "A4")
	(title_block
		(title "04192023_DAF0TMB3IC0_F0TG_MB_C_brd_V02_OCP.brd")
		(comment 1 "Grand Teton / footprints 8152-8153 of 8354")
	)
	(layers
		(0 "F.Cu" signal "TOP")
		(4 "In1.Cu" signal "GND")
		(6 "In2.Cu" signal "IN1")
		(8 "In3.Cu" signal "GND1")
		(10 "In4.Cu" signal "IN2")
		(12 "In5.Cu" signal "GND2")
		(14 "In6.Cu" signal "IN3")
		(16 "In7.Cu" signal "GND3")
		(18 "In8.Cu" signal "VCC")
		(20 "In9.Cu" signal "VCC1")
		(22 "In10.Cu" signal "GND4")
		(24 "In11.Cu" signal "IN4")
		(26 "In12.Cu" signal "GND5")
		(28 "In13.Cu" signal "IN5")
		(30 "In14.Cu" signal "GND6")
		(32 "In15.Cu" signal "IN6")
		(34 "In16.Cu" signal "GND7")
		(2 "B.Cu" signal "BOTTOM")
		(9 "F.Adhes" user "F.Adhesive")
		(11 "B.Adhes" user "B.Adhesive")
		(13 "F.Paste" user "Package Geometry/Pastemask Top")
		(15 "B.Paste" user "Package Geometry/Pastemask Bottom")
		(5 "F.SilkS" user "Ref Des/Silkscreen Top")
		(7 "B.SilkS" user "Ref Des/Silkscreen Bottom")
		(1 "F.Mask" user "Board Geometry/Soldermask Top")
		(3 "B.Mask" user "Board Geometry/Soldermask Bottom")
		(17 "Dwgs.User" user "User.Drawings")
		(19 "Cmts.User" user "User.Comments")
		(21 "Eco1.User" user "User.Eco1")
		(23 "Eco2.User" user "User.Eco2")
		(25 "Edge.Cuts" user "Board Geometry/Outline")
		(27 "Margin" user)
		(31 "F.CrtYd" user "Package Geometry/Place Bound Top")
		(29 "B.CrtYd" user "Package Geometry/Place Bound Bottom")
		(35 "F.Fab" user "Ref Des/Assembly Top")
		(33 "B.Fab" user "Ref Des/Assembly Bottom")
	)
	(footprint ""
		(layer "B.Cu")
		(at 88.138 -147.955 180)
		(property "Reference" "PR8009"
			(at 0 0 0)
			(layer "B.SilkS")
			(hide yes)
			(effects
				(font
					(size 1.27 1.27)
				)
				(justify mirror)
			)
		)
		(property "Value" ""
			(at 0 0 0)
			(layer "B.Fab")
			(effects
				(font
					(size 1.27 1.27)
				)
				(justify mirror)
			)
		)
		(duplicate_pad_numbers_are_jumpers no)
		(fp_line
			(start 0.7874 0.4064)
			(end 0.7874 -0.4064)
			(stroke
				(width 0.1524)
				(type default)
			)
			(layer "B.SilkS")
		)
		(fp_line
			(start 0.7874 -0.4064)
			(end -0.7874 -0.4064)
			(stroke
				(width 0.1524)
				(type default)
			)
			(layer "B.SilkS")
		)
		(fp_line
			(start -0.7874 0.4064)
			(end 0.7874 0.4064)
			(stroke
				(width 0.1524)
				(type default)
			)
			(layer "B.SilkS")
		)
		(fp_line
			(start -0.7874 -0.4064)
			(end -0.7874 0.4064)
			(stroke
				(width 0.1524)
				(type default)
			)
			(layer "B.SilkS")
		)
		(fp_line
			(start 0.67945 0.3048)
			(end 0.67945 -0.305054)
			(stroke
				(width 0.1)
				(type default)
			)
			(layer "B.Fab")
		)
		(fp_line
			(start 0.67945 -0.305054)
			(end 0.12065 -0.305054)
			(stroke
				(width 0.1)
				(type default)
			)
			(layer "B.Fab")
		)
		(fp_line
			(start 0.12065 0.3048)
			(end 0.67945 0.3048)
			(stroke
				(width 0.1)
				(type default)
			)
			(layer "B.Fab")
		)
		(fp_line
			(start 0.12065 0.2794)
			(end 0.12065 0.3048)
			(stroke
				(width 0.1)
				(type default)
			)
			(layer "B.Fab")
		)
		(fp_line
			(start 0.12065 -0.2794)
			(end -0.12065 -0.2794)
			(stroke
				(width 0.1)
				(type default)
			)
			(layer "B.Fab")
		)
		(fp_line
			(start 0.12065 -0.305054)
			(end 0.12065 -0.2794)
			(stroke
				(width 0.1)
				(type default)
			)
			(layer "B.Fab")
		)
		(fp_line
			(start -0.120396 0.3048)
			(end -0.120396 0.2794)
			(stroke
				(width 0.1)
				(type default)
			)
			(layer "B.Fab")
		)
		(fp_line
			(start -0.120396 0.2794)
			(end 0.12065 0.2794)
			(stroke
				(width 0.1)
				(type default)
			)
			(layer "B.Fab")
		)
		(fp_line
			(start -0.12065 -0.2794)
			(end -0.12065 -0.3048)
			(stroke
				(width 0.1)
				(type default)
			)
			(layer "B.Fab")
		)
		(fp_line
			(start -0.12065 -0.3048)
			(end -0.67945 -0.3048)
			(stroke
				(width 0.1)
				(type default)
			)
			(layer "B.Fab")
		)
		(fp_line
			(start -0.67945 0.3048)
			(end -0.120396 0.3048)
			(stroke
				(width 0.1)
				(type default)
			)
			(layer "B.Fab")
		)
		(fp_line
			(start -0.67945 -0.3048)
			(end -0.67945 0.3048)
			(stroke
				(width 0.1)
				(type default)
			)
			(layer "B.Fab")
		)
		(pad "1" smd circle
			(at 0.40005 0)
			(size 0 0)
			(layers "B.Cu" "B.Mask" "B.Paste")
			(net "SVID_PVDDCR_CPU0_P1_SVC_R")
		)
		(pad "2" smd circle
			(at -0.40005 0)
			(size 0 0)
			(layers "B.Cu" "B.Mask" "B.Paste")
			(net "SVID_PVDDCR_CPU0_P1_SVC_R1")
		)
	)
	(footprint ""
		(layer "B.Cu")
		(at 369.646454 -250.89231)
		(property "Reference" "C2557"
			(at 0 0 0)
			(layer "B.SilkS")
			(hide yes)
			(effects
				(font
					(size 1.27 1.27)
				)
				(justify mirror)
			)
		)
		(property "Value" ""
			(at 0 0 0)
			(layer "B.Fab")
			(effects
				(font
					(size 1.27 1.27)
				)
				(justify mirror)
			)
		)
		(duplicate_pad_numbers_are_jumpers no)
		(fp_line
			(start -0.7874 -0.4064)
			(end -0.7874 0.4064)
			(stroke
				(width 0.1524)
				(type default)
			)
			(layer "B.SilkS")
		)
		(fp_line
			(start -0.7874 0.4064)
			(end 0.7874 0.4064)
			(stroke
				(width 0.1524)
				(type default)
			)
			(layer "B.SilkS")
		)
		(fp_line
			(start 0.7874 -0.4064)
			(end -0.7874 -0.4064)
			(stroke
				(width 0.1524)
				(type default)
			)
			(layer "B.SilkS")
		)
		(fp_line
			(start 0.7874 0.4064)
			(end 0.7874 -0.4064)
			(stroke
				(width 0.1524)
				(type default)
			)
			(layer "B.SilkS")
		)
		(fp_line
			(start -0.67945 -0.3048)
			(end -0.67945 0.3048)
			(stroke
				(width 0.1)
				(type default)
			)
			(layer "B.Fab")
		)
		(fp_line
			(start -0.67945 0.3048)
			(end -0.120396 0.3048)
			(stroke
				(width 0.1)
				(type default)
			)
			(layer "B.Fab")
		)
		(fp_line
			(start -0.12065 -0.3048)
			(end -0.67945 -0.3048)
			(stroke
				(width 0.1)
				(type default)
			)
			(layer "B.Fab")
		)
		(fp_line
			(start -0.12065 -0.2794)
			(end -0.12065 -0.3048)
			(stroke
				(width 0.1)
				(type default)
			)
			(layer "B.Fab")
		)
		(fp_line
			(start -0.120396 0.2794)
			(end 0.12065 0.2794)
			(stroke
				(width 0.1)
				(type default)
			)
			(layer "B.Fab")
		)
		(fp_line
			(start -0.120396 0.3048)
			(end -0.120396 0.2794)
			(stroke
				(width 0.1)
				(type default)
			)
			(layer "B.Fab")
		)
		(fp_line
			(start 0.12065 -0.305054)
			(end 0.12065 -0.2794)
			(stroke
				(width 0.1)
				(type default)
			)
			(layer "B.Fab")
		)
		(fp_line
			(start 0.12065 -0.2794)
			(end -0.12065 -0.2794)
			(stroke
				(width 0.1)
				(type default)
			)
			(layer "B.Fab")
		)
		(fp_line
			(start 0.12065 0.2794)
			(end 0.12065 0.3048)
			(stroke
				(width 0.1)
				(type default)
			)
			(layer "B.Fab")
		)
		(fp_line
			(start 0.12065 0.3048)
			(end 0.67945 0.3048)
			(stroke
				(width 0.1)
				(type default)
			)
			(layer "B.Fab")
		)
		(fp_line
			(start 0.67945 -0.305054)
			(end 0.12065 -0.305054)
			(stroke
				(width 0.1)
				(type default)
			)
			(layer "B.Fab")
		)
		(fp_line
			(start 0.67945 0.3048)
			(end 0.67945 -0.305054)
			(stroke
				(width 0.1)
				(type default)
			)
			(layer "B.Fab")
		)
		(pad "1" smd circle
			(at 0.40005 0 180)
			(size 0 0)
			(layers "B.Cu" "B.Mask" "B.Paste")
			(net "PVDDCR_SOC_P0")
		)
		(pad "2" smd circle
			(at -0.40005 0 180)
			(size 0 0)
			(layers "B.Cu" "B.Mask" "B.Paste")
			(net "GND")
		)
	)
)
